# T6G (Grand Teton) — schematic netlist excerpt (pin names and nets, part order shuffled) for the footprints in the layout excerpt that follows; sources: Cadence DE-HDL packaged netlist, KiCad conversion of 04192023_DAF0TMB3IC0_F0TG_MB_C_brd_V02_OCP.brd

J27  SCONN288_DDR506112002KQ  IO  pkg DDR288S_1-1VXC  page 105
  VIN_BULK0  = P12V_MEM_CPU1
  RFU0  = NC
  VIN_MGMT  = P3V3_AUX
  HSCL  = I3C_SPD_DDRH_CPU1_SCL
  HSDA  = I3C_SPD_DDRH_CPU1_SDA
  VSS0  = GND
  DQ0_A  = M_H_CPU1_SA_DQ<0>
  VSS1  = GND
  DQ1_A  = M_H_CPU1_SA_DQ<1>
  VSS2  = GND
  DQS0_A_T  = M_H_CPU1_SA_DQS_DP<0>
  DQS0_A_C  = M_H_CPU1_SA_DQS_DN<0>
  VSS3  = GND
  DQ4_A  = M_H_CPU1_SA_DQ<4>
  VSS4  = GND
  DQ5_A  = M_H_CPU1_SA_DQ<5>
  VSS5  = GND
  DQ8_A  = M_H_CPU1_SA_DQ<8>
  VSS6  = GND
  DQ9_A  = M_H_CPU1_SA_DQ<9>
  VSS7  = GND
  DQS1_A_T  = M_H_CPU1_SA_DQS_DP<1>
  DQS1_A_C  = M_H_CPU1_SA_DQS_DN<1>
  VSS8  = GND
  DQ12_A  = M_H_CPU1_SA_DQ<12>
  VSS9  = GND
  DQ13_A  = M_H_CPU1_SA_DQ<13>
  VSS10  = GND
  DQ16_A  = M_H_CPU1_SA_DQ<16>
  VSS11  = GND
  DQ17_A  = M_H_CPU1_SA_DQ<17>
  VSS12  = GND
  DQS2_A_T  = M_H_CPU1_SA_DQS_DP<2>
  DQS2_A_C  = M_H_CPU1_SA_DQS_DN<2>
  VSS13  = GND
  DQ20_A  = M_H_CPU1_SA_DQ<20>
  VSS14  = GND
  DQ21_A  = M_H_CPU1_SA_DQ<21>
  VSS15  = GND
  DQ24_A  = M_H_CPU1_SA_DQ<24>
  VSS16  = GND
  DQ25_A  = M_H_CPU1_SA_DQ<25>
  VSS17  = GND
  DQS3_A_T  = M_H_CPU1_SA_DQS_DP<3>
  DQS3_A_C  = M_H_CPU1_SA_DQS_DN<3>
  VSS18  = GND
  DQ28_A  = M_H_CPU1_SA_DQ<28>
  VSS19  = GND
  DQ29_A  = M_H_CPU1_SA_DQ<29>
  VSS20  = GND
  CB0_A  = M_H_CPU1_SA_CB<0>
  VSS21  = GND
  CB1_A  = M_H_CPU1_SA_CB<1>
  VSS22  = GND
  DQS4_A_T  = M_H_CPU1_SA_DQS_DP<4>
  DQS4_A_C  = M_H_CPU1_SA_DQS_DN<4>
  VSS23  = GND
  CB4_A  = M_H_CPU1_SA_CB<4>
  VSS24  = GND
  CB5_A  = M_H_CPU1_SA_CB<5>
  VSS25  = GND
  ALERT_N  = M_H_CPU1_ALERT_N
  VSS26  = GND
  CS0_A_N  = M_H_CPU1_SA_CS_N<0>
  VSS27  = GND
  CA0_A  = M_H_CPU1_SA_CA<0>
  VSS28  = GND
  CA2_A  = M_H_CPU1_SA_CA<2>
  VSS29  = GND
  CA4_A  = M_H_CPU1_SA_CA<4>
  VSS30  = GND
  CA6_A  = M_H_CPU1_SA_CA<6>
  VSS31  = GND
  PAR_A  = M_H_CPU1_SA_PAR
  VSS32  = GND
  CA0_B  = M_H_CPU1_SB_CA<0>
  VSS33  = GND
  CA2_B  = M_H_CPU1_SB_CA<2>
  VSS34  = GND
  CA4_B  = M_H_CPU1_SB_CA<4>
  VSS35  = GND
  CA6_B  = M_H_CPU1_SB_CA<6>
  VSS36  = GND
  CS0_B_N  = M_H_CPU1_SB_CS_N<0>
  VSS37  = GND
  \lbd||rsp_a_n\  = M_H_CPU1_SA_RSP<0>
  \lbs||rsp_b_n\  = M_H_CPU1_SB_RSP<0>
  VSS38  = GND
  CB4_B  = M_H_CPU1_SB_CB<4>
  VSS39  = GND
  CB5_B  = M_H_CPU1_SB_CB<5>
  VSS40  = GND
  \dqs9_b_t||tdqs9_b_t||dbi4_b_n\  = M_H_CPU1_SB_DQS_DP<9>
  \dqs9_b_c||tdqs9_b_c\  = M_H_CPU1_SB_DQS_DN<9>
  VSS41  = GND
  CB0_B  = M_H_CPU1_SB_CB<0>
  VSS42  = GND
  CB1_B  = M_H_CPU1_SB_CB<1>
  VSS43  = GND
  DQ0_B  = M_H_CPU1_SB_DQ<0>
  VSS44  = GND
  DQ1_B  = M_H_CPU1_SB_DQ<1>
  VSS45  = GND
  DQS0_B_T  = M_H_CPU1_SB_DQS_DP<0>
  DQS0_B_C  = M_H_CPU1_SB_DQS_DN<0>
  VSS46  = GND
  DQ4_B  = M_H_CPU1_SB_DQ<4>
  VSS47  = GND
  DQ5_B  = M_H_CPU1_SB_DQ<5>
  VSS48  = GND
  DQ8_B  = M_H_CPU1_SB_DQ<8>
  VSS49  = GND
  DQ9_B  = M_H_CPU1_SB_DQ<9>
  VSS50  = GND
  DQS1_B_T  = M_H_CPU1_SB_DQS_DP<1>
  DQS1_B_C  = M_H_CPU1_SB_DQS_DN<1>
  VSS51  = GND
  DQ12_B  = M_H_CPU1_SB_DQ<12>
  VSS52  = GND
  DQ13_B  = M_H_CPU1_SB_DQ<13>
  VSS53  = GND
  DQ16_B  = M_H_CPU1_SB_DQ<16>
  VSS54  = GND
  DQ17_B  = M_H_CPU1_SB_DQ<17>
  VSS55  = GND
  DQS2_B_T  = M_H_CPU1_SB_DQS_DP<2>
  DQS2_B_C  = M_H_CPU1_SB_DQS_DN<2>
  VSS56  = GND
  DQ20_B  = M_H_CPU1_SB_DQ<20>
  VSS57  = GND
  DQ21_B  = M_H_CPU1_SB_DQ<21>
  VSS58  = GND
  DQ24_B  = M_H_CPU1_SB_DQ<24>
  VSS59  = GND
  DQ25_B  = M_H_CPU1_SB_DQ<25>
  VSS60  = GND
  DQS3_B_T  = M_H_CPU1_SB_DQS_DP<3>
  DQS3_B_C  = M_H_CPU1_SB_DQS_DN<3>
  VSS61  = GND
  DQ28_B  = M_H_CPU1_SB_DQ<28>
  VSS62  = GND
  DQ29_B  = M_H_CPU1_SB_DQ<29>
  VSS63  = GND
  RFU1  = NC
  VIN_BULK1  = P12V_MEM_CPU1
  VIN_BULK2  = P12V_MEM_CPU1
  \pwr_good||fail_n\  = PWRGD_CHH_CPU1_DIMM
  HAS  = PD_CHH_CPU1_DIMM_SAA
  RFU2  = NC
  RFU3  = NC
  VSS64  = GND
  DQ2_A  = M_H_CPU1_SA_DQ<2>
  VSS65  = GND
  DQ3_A  = M_H_CPU1_SA_DQ<3>
  VSS66  = GND
  \dqs5_a_c||tdqs5_a_c||dqs5_a_t||tdqs5_a_t\  = M_H_CPU1_SA_DQS_DN<5>
  \dqs5_a_t||tdqs5_a_t\  = M_H_CPU1_SA_DQS_DP<5>
  VSS67  = GND
  DQ6_A  = M_H_CPU1_SA_DQ<6>
  VSS68  = GND
  DQ7_A  = M_H_CPU1_SA_DQ<7>
  VSS69  = GND
  DQ10_A  = M_H_CPU1_SA_DQ<10>
  VSS70  = GND
  DQ11_A  = M_H_CPU1_SA_DQ<11>
  VSS71  = GND
  \dqs6_a_c||tdqs6_a_c||dqs6_a_t||tdqs6_a_t\  = M_H_CPU1_SA_DQS_DN<6>
  \dqs6_a_t||tdqs6_a_t\  = M_H_CPU1_SA_DQS_DP<6>
  VSS72  = GND
  DQ14_A  = M_H_CPU1_SA_DQ<14>
  VSS73  = GND
  DQ15_A  = M_H_CPU1_SA_DQ<15>
  VSS74  = GND
  DQ18_A  = M_H_CPU1_SA_DQ<18>
  VSS75  = GND
  DQ19_A  = M_H_CPU1_SA_DQ<19>
  VSS76  = GND
  \dqs7_a_c||tdqs7_a_c\  = M_H_CPU1_SA_DQS_DN<7>
  \dqs7_a_t||tdqs7_a_t\  = M_H_CPU1_SA_DQS_DP<7>
  VSS77  = GND
  DQ22_A  = M_H_CPU1_SA_DQ<22>
  VSS78  = GND
  DQ23_A  = M_H_CPU1_SA_DQ<23>
  VSS79  = GND
  DQ26_A  = M_H_CPU1_SA_DQ<26>
  VSS80  = GND
  DQ27_A  = M_H_CPU1_SA_DQ<27>
  VSS81  = GND
  \dqs8_a_c||tdqs8_a_c\  = M_H_CPU1_SA_DQS_DN<8>
  \dqs8_a_t||tdqs8_a_t\  = M_H_CPU1_SA_DQS_DP<8>
  VSS82  = GND
  DQ30_A  = M_H_CPU1_SA_DQ<30>
  VSS83  = GND
  DQ31_A  = M_H_CPU1_SA_DQ<31>
  VSS84  = GND
  CB2_A  = M_H_CPU1_SA_CB<2>
  VSS85  = GND
  CB3_A  = M_H_CPU1_SA_CB<3>
  VSS86  = GND
  \dqs9_a_c||tdqs9_a_c\  = M_H_CPU1_SA_DQS_DN<9>
  \dqs9_a_t||tdqs9_a_t\  = M_H_CPU1_SA_DQS_DP<9>
  VSS87  = GND
  CB6_A  = M_H_CPU1_SA_CB<6>
  VSS88  = GND
  CB7_A  = M_H_CPU1_SA_CB<7>
  VSS89  = GND
  RESET_N  = M_H_CPU1_RESET_N
  VSS90  = GND
  CS1_A_N  = M_H_CPU1_SA_CS_N<1>
  VSS91  = GND
  CA1_A  = M_H_CPU1_SA_CA<1>
  VSS92  = GND
  CA3_A  = M_H_CPU1_SA_CA<3>
  VSS93  = GND
  CA5_A  = M_H_CPU1_SA_CA<5>
  VSS94  = GND
  CK_T  = M_H_CPU1_CLK_DP<0>
  CK_C  = M_H_CPU1_CLK_DN<0>
  VSS95  = GND
  RFU4  = NC
  CA1_B  = M_H_CPU1_SB_CA<1>
  VSS96  = GND
  CA3_B  = M_H_CPU1_SB_CA<3>
  VSS97  = GND
  CA5_B  = M_H_CPU1_SB_CA<5>
  VSS98  = GND
  PAR_B  = M_H_CPU1_SB_PAR
  VSS99  = GND
  CS1_B_N  = M_H_CPU1_SB_CS_N<1>
  VSS100  = GND
  RFU5  = NC
  RFU6  = NC
  VSS101  = GND
  CB6_B  = M_H_CPU1_SB_CB<6>
  VSS102  = GND
  CB7_B  = M_H_CPU1_SB_CB<7>
  VSS103  = GND
  DQS4_B_C  = M_H_CPU1_SB_DQS_DN<4>
  DQS4_B_T  = M_H_CPU1_SB_DQS_DP<4>
  VSS104  = GND
  CB2_B  = M_H_CPU1_SB_CB<2>
  VSS105  = GND
  CB3_B  = M_H_CPU1_SB_CB<3>
  VSS106  = GND
  DQ2_B  = M_H_CPU1_SB_DQ<2>
  VSS107  = GND
  DQ3_B  = M_H_CPU1_SB_DQ<3>
  VSS108  = GND
  \dqs5_b_c||tdqs5_b_c\  = M_H_CPU1_SB_DQS_DN<5>
  \dqs5_b_t||tdqs5_b_t\  = M_H_CPU1_SB_DQS_DP<5>
  VSS109  = GND
  DQ6_B  = M_H_CPU1_SB_DQ<6>
  VSS110  = GND
  DQ7_B  = M_H_CPU1_SB_DQ<7>
  VSS111  = GND
  DQ10_B  = M_H_CPU1_SB_DQ<10>
  VSS112  = GND
  DQ11_B  = M_H_CPU1_SB_DQ<11>
  VSS113  = GND
  \dqs6_b_c||tdqs6_b_c\  = M_H_CPU1_SB_DQS_DN<6>
  \dqs6_b_t||tdqs6_b_t\  = M_H_CPU1_SB_DQS_DP<6>
  VSS114  = GND
  DQ14_B  = M_H_CPU1_SB_DQ<14>
  VSS115  = GND
  DQ15_B  = M_H_CPU1_SB_DQ<15>
  VSS116  = GND
  DQ18_B  = M_H_CPU1_SB_DQ<18>
  VSS117  = GND
  DQ19_B  = M_H_CPU1_SB_DQ<19>
  VSS118  = GND
  \dqs7_b_c||tdqs7_b_c\  = M_H_CPU1_SB_DQS_DN<7>
  \dqs7_b_t||tdqs7_b_t\  = M_H_CPU1_SB_DQS_DP<7>
  VSS119  = GND
  DQ22_B  = M_H_CPU1_SB_DQ<22>
  VSS120  = GND
  DQ23_B  = M_H_CPU1_SB_DQ<23>
  VSS121  = GND
  DQ26_B  = M_H_CPU1_SB_DQ<26>
  VSS122  = GND
  DQ27_B  = M_H_CPU1_SB_DQ<27>
  VSS123  = GND
  \dqs8_b_c||tdqs8_b_c\  = M_H_CPU1_SB_DQS_DN<8>
  \dqs8_b_t||tdqs8_b_t\  = M_H_CPU1_SB_DQS_DP<8>
  VSS124  = GND
  DQ30_B  = M_H_CPU1_SB_DQ<30>
  VSS125  = GND
  DQ31_B  = M_H_CPU1_SB_DQ<31>
  VSS126  = GND
  G1  = GND
  G2  = GND
  G3  = GND

(kicad_pcb
	(version 20260206)
	(generator "pcbnew")
	(generator_version "10.0")
	(general
		(thickness 1.6)
		(legacy_teardrops no)
	)
	(paper "A4")
	(title_block
		(title "04192023_DAF0TMB3IC0_F0TG_MB_C_brd_V02_OCP.brd")
		(comment 1 "Grand Teton / footprint 583 of 8354 (J27), pads 93-138 of 291")
	)
	(layers
		(0 "F.Cu" signal "TOP")
		(4 "In1.Cu" signal "GND")
		(6 "In2.Cu" signal "IN1")
		(8 "In3.Cu" signal "GND1")
		(10 "In4.Cu" signal "IN2")
		(12 "In5.Cu" signal "GND2")
		(14 "In6.Cu" signal "IN3")
		(16 "In7.Cu" signal "GND3")
		(18 "In8.Cu" signal "VCC")
		(20 "In9.Cu" signal "VCC1")
		(22 "In10.Cu" signal "GND4")
		(24 "In11.Cu" signal "IN4")
		(26 "In12.Cu" signal "GND5")
		(28 "In13.Cu" signal "IN5")
		(30 "In14.Cu" signal "GND6")
		(32 "In15.Cu" signal "IN6")
		(34 "In16.Cu" signal "GND7")
		(2 "B.Cu" signal "BOTTOM")
		(9 "F.Adhes" user "F.Adhesive")
		(11 "B.Adhes" user "B.Adhesive")
		(13 "F.Paste" user "Package Geometry/Pastemask Top")
		(15 "B.Paste" user "Package Geometry/Pastemask Bottom")
		(5 "F.SilkS" user "Ref Des/Silkscreen Top")
		(7 "B.SilkS" user "Ref Des/Silkscreen Bottom")
		(1 "F.Mask" user "Board Geometry/Soldermask Top")
		(3 "B.Mask" user "Board Geometry/Soldermask Bottom")
		(17 "Dwgs.User" user "User.Drawings")
		(19 "Cmts.User" user "User.Comments")
		(21 "Eco1.User" user "User.Eco1")
		(23 "Eco2.User" user "User.Eco2")
		(25 "Edge.Cuts" user "Board Geometry/Outline")
		(27 "Margin" user)
		(31 "F.CrtYd" user "Package Geometry/Place Bound Top")
		(29 "B.CrtYd" user "Package Geometry/Place Bound Bottom")
		(35 "F.Fab" user "Ref Des/Assembly Top")
		(33 "B.Fab" user "Ref Des/Assembly Bottom")
	)
	(footprint ""
		(layer "F.Cu")
		(at 174.022004 -255.560322 180)
		(property "Reference" "J27"
			(at -2.7178 -81.857088 0)
			(unlocked yes)
			(layer "F.SilkS")
			(effects
				(font
					(size 0.7874 0.5842)
					(thickness 0.1524)
				)
			)
		)
		(property "Value" ""
			(at 0 0 180)
			(layer "F.Fab")
			(effects
				(font
					(size 1.27 1.27)
				)
			)
		)
		(duplicate_pad_numbers_are_jumpers no)
		(pad "93" smd rect
			(at -2.050034 19.975068 90)
			(size 0.519938 1.4986)
			(layers "F.Cu" "F.Mask" "F.Paste")
			(net "M_H_CPU1_SB_DQS_DP<9>")
		)
		(pad "94" smd rect
			(at -2.050034 20.824952 90)
			(size 0.519938 1.4986)
			(layers "F.Cu" "F.Mask" "F.Paste")
			(net "M_H_CPU1_SB_DQS_DN<9>")
		)
		(pad "95" smd rect
			(at -2.050034 21.67509 90)
			(size 0.519938 1.4986)
			(layers "F.Cu" "F.Mask" "F.Paste")
			(net "GND")
		)
		(pad "96" smd rect
			(at -2.050034 22.524974 90)
			(size 0.519938 1.4986)
			(layers "F.Cu" "F.Mask" "F.Paste")
			(net "M_H_CPU1_SB_CB<0>")
		)
		(pad "97" smd rect
			(at -2.050034 23.375112 90)
			(size 0.519938 1.4986)
			(layers "F.Cu" "F.Mask" "F.Paste")
			(net "GND")
		)
		(pad "98" smd rect
			(at -2.050034 24.224996 90)
			(size 0.519938 1.4986)
			(layers "F.Cu" "F.Mask" "F.Paste")
			(net "M_H_CPU1_SB_CB<1>")
		)
		(pad "99" smd rect
			(at -2.050034 25.07488 90)
			(size 0.519938 1.4986)
			(layers "F.Cu" "F.Mask" "F.Paste")
			(net "GND")
		)
		(pad "100" smd rect
			(at -2.050034 25.925018 90)
			(size 0.519938 1.4986)
			(layers "F.Cu" "F.Mask" "F.Paste")
			(net "M_H_CPU1_SB_DQ<0>")
		)
		(pad "101" smd rect
			(at -2.050034 26.774902 90)
			(size 0.519938 1.4986)
			(layers "F.Cu" "F.Mask" "F.Paste")
			(net "GND")
		)
		(pad "102" smd rect
			(at -2.050034 27.62504 90)
			(size 0.519938 1.4986)
			(layers "F.Cu" "F.Mask" "F.Paste")
			(net "M_H_CPU1_SB_DQ<1>")
		)
		(pad "103" smd rect
			(at -2.050034 28.474924 90)
			(size 0.519938 1.4986)
			(layers "F.Cu" "F.Mask" "F.Paste")
			(net "GND")
		)
		(pad "104" smd rect
			(at -2.050034 29.325062 90)
			(size 0.519938 1.4986)
			(layers "F.Cu" "F.Mask" "F.Paste")
			(net "M_H_CPU1_SB_DQS_DP<0>")
		)
		(pad "105" smd rect
			(at -2.050034 30.174946 90)
			(size 0.519938 1.4986)
			(layers "F.Cu" "F.Mask" "F.Paste")
			(net "M_H_CPU1_SB_DQS_DN<0>")
		)
		(pad "106" smd rect
			(at -2.050034 31.025084 90)
			(size 0.519938 1.4986)
			(layers "F.Cu" "F.Mask" "F.Paste")
			(net "GND")
		)
		(pad "107" smd rect
			(at -2.050034 31.874968 90)
			(size 0.519938 1.4986)
			(layers "F.Cu" "F.Mask" "F.Paste")
			(net "M_H_CPU1_SB_DQ<4>")
		)
		(pad "108" smd rect
			(at -2.050034 32.725106 90)
			(size 0.519938 1.4986)
			(layers "F.Cu" "F.Mask" "F.Paste")
			(net "GND")
		)
		(pad "109" smd rect
			(at -2.050034 33.57499 90)
			(size 0.519938 1.4986)
			(layers "F.Cu" "F.Mask" "F.Paste")
			(net "M_H_CPU1_SB_DQ<5>")
		)
		(pad "110" smd rect
			(at -2.050034 34.425128 90)
			(size 0.519938 1.4986)
			(layers "F.Cu" "F.Mask" "F.Paste")
			(net "GND")
		)
		(pad "111" smd rect
			(at -2.050034 35.275012 90)
			(size 0.519938 1.4986)
			(layers "F.Cu" "F.Mask" "F.Paste")
			(net "M_H_CPU1_SB_DQ<8>")
		)
		(pad "112" smd rect
			(at -2.050034 36.124896 90)
			(size 0.519938 1.4986)
			(layers "F.Cu" "F.Mask" "F.Paste")
			(net "GND")
		)
		(pad "113" smd rect
			(at -2.050034 36.975034 90)
			(size 0.519938 1.4986)
			(layers "F.Cu" "F.Mask" "F.Paste")
			(net "M_H_CPU1_SB_DQ<9>")
		)
		(pad "114" smd rect
			(at -2.050034 37.824918 90)
			(size 0.519938 1.4986)
			(layers "F.Cu" "F.Mask" "F.Paste")
			(net "GND")
		)
		(pad "115" smd rect
			(at -2.050034 38.675056 90)
			(size 0.519938 1.4986)
			(layers "F.Cu" "F.Mask" "F.Paste")
			(net "M_H_CPU1_SB_DQS_DP<1>")
		)
		(pad "116" smd rect
			(at -2.050034 39.52494 90)
			(size 0.519938 1.4986)
			(layers "F.Cu" "F.Mask" "F.Paste")
			(net "M_H_CPU1_SB_DQS_DN<1>")
		)
		(pad "117" smd rect
			(at -2.050034 40.375078 90)
			(size 0.519938 1.4986)
			(layers "F.Cu" "F.Mask" "F.Paste")
			(net "GND")
		)
		(pad "118" smd rect
			(at -2.050034 41.224962 90)
			(size 0.519938 1.4986)
			(layers "F.Cu" "F.Mask" "F.Paste")
			(net "M_H_CPU1_SB_DQ<12>")
		)
		(pad "119" smd rect
			(at -2.050034 42.0751 90)
			(size 0.519938 1.4986)
			(layers "F.Cu" "F.Mask" "F.Paste")
			(net "GND")
		)
		(pad "120" smd rect
			(at -2.050034 42.924984 90)
			(size 0.519938 1.4986)
			(layers "F.Cu" "F.Mask" "F.Paste")
			(net "M_H_CPU1_SB_DQ<13>")
		)
		(pad "121" smd rect
			(at -2.050034 43.775122 90)
			(size 0.519938 1.4986)
			(layers "F.Cu" "F.Mask" "F.Paste")
			(net "GND")
		)
		(pad "122" smd rect
			(at -2.050034 44.625006 90)
			(size 0.519938 1.4986)
			(layers "F.Cu" "F.Mask" "F.Paste")
			(net "M_H_CPU1_SB_DQ<16>")
		)
		(pad "123" smd rect
			(at -2.050034 45.47489 90)
			(size 0.519938 1.4986)
			(layers "F.Cu" "F.Mask" "F.Paste")
			(net "GND")
		)
		(pad "124" smd rect
			(at -2.050034 46.325028 90)
			(size 0.519938 1.4986)
			(layers "F.Cu" "F.Mask" "F.Paste")
			(net "M_H_CPU1_SB_DQ<17>")
		)
		(pad "125" smd rect
			(at -2.050034 47.174912 90)
			(size 0.519938 1.4986)
			(layers "F.Cu" "F.Mask" "F.Paste")
			(net "GND")
		)
		(pad "126" smd rect
			(at -2.050034 48.02505 90)
			(size 0.519938 1.4986)
			(layers "F.Cu" "F.Mask" "F.Paste")
			(net "M_H_CPU1_SB_DQS_DP<2>")
		)
		(pad "127" smd rect
			(at -2.050034 48.874934 90)
			(size 0.519938 1.4986)
			(layers "F.Cu" "F.Mask" "F.Paste")
			(net "M_H_CPU1_SB_DQS_DN<2>")
		)
		(pad "128" smd rect
			(at -2.050034 49.725072 90)
			(size 0.519938 1.4986)
			(layers "F.Cu" "F.Mask" "F.Paste")
			(net "GND")
		)
		(pad "129" smd rect
			(at -2.050034 50.574956 90)
			(size 0.519938 1.4986)
			(layers "F.Cu" "F.Mask" "F.Paste")
			(net "M_H_CPU1_SB_DQ<20>")
		)
		(pad "130" smd rect
			(at -2.050034 51.425094 90)
			(size 0.519938 1.4986)
			(layers "F.Cu" "F.Mask" "F.Paste")
			(net "GND")
		)
		(pad "131" smd rect
			(at -2.050034 52.274978 90)
			(size 0.519938 1.4986)
			(layers "F.Cu" "F.Mask" "F.Paste")
			(net "M_H_CPU1_SB_DQ<21>")
		)
		(pad "132" smd rect
			(at -2.050034 53.125116 90)
			(size 0.519938 1.4986)
			(layers "F.Cu" "F.Mask" "F.Paste")
			(net "GND")
		)
		(pad "133" smd rect
			(at -2.050034 53.975 90)
			(size 0.519938 1.4986)
			(layers "F.Cu" "F.Mask" "F.Paste")
			(net "M_H_CPU1_SB_DQ<24>")
		)
		(pad "134" smd rect
			(at -2.050034 54.824884 90)
			(size 0.519938 1.4986)
			(layers "F.Cu" "F.Mask" "F.Paste")
			(net "GND")
		)
		(pad "135" smd rect
			(at -2.050034 55.675022 90)
			(size 0.519938 1.4986)
			(layers "F.Cu" "F.Mask" "F.Paste")
			(net "M_H_CPU1_SB_DQ<25>")
		)
		(pad "136" smd rect
			(at -2.050034 56.524906 90)
			(size 0.519938 1.4986)
			(layers "F.Cu" "F.Mask" "F.Paste")
			(net "GND")
		)
		(pad "137" smd rect
			(at -2.050034 57.375044 90)
			(size 0.519938 1.4986)
			(layers "F.Cu" "F.Mask" "F.Paste")
			(net "M_H_CPU1_SB_DQS_DP<3>")
		)
		(pad "138" smd rect
			(at -2.050034 58.224928 90)
			(size 0.519938 1.4986)
			(layers "F.Cu" "F.Mask" "F.Paste")
			(net "M_H_CPU1_SB_DQS_DN<3>")
		)
	)
)
